(kicad_pcb
	(version 20260206)
	(generator "pcbnew")
	(generator_version "10.0")
	(general
		(thickness 1.6)
		(legacy_teardrops no)
	)
	(paper "A4")
	(title_block
		(title "04192023_DAF0TMB3IC0_F0TG_MB_C_brd_V02_OCP.brd")
		(comment 1 "Grand Teton / footprint 3166 of 8354 (J41), pads 1-107 of 175")
	)
	(layers
		(0 "F.Cu" signal "TOP")
		(4 "In1.Cu" signal "GND")
		(6 "In2.Cu" signal "IN1")
		(8 "In3.Cu" signal "GND1")
		(10 "In4.Cu" signal "IN2")
		(12 "In5.Cu" signal "GND2")
		(14 "In6.Cu" signal "IN3")
		(16 "In7.Cu" signal "GND3")
		(18 "In8.Cu" signal "VCC")
		(20 "In9.Cu" signal "VCC1")
		(22 "In10.Cu" signal "GND4")
		(24 "In11.Cu" signal "IN4")
		(26 "In12.Cu" signal "GND5")
		(28 "In13.Cu" signal "IN5")
		(30 "In14.Cu" signal "GND6")
		(32 "In15.Cu" signal "IN6")
		(34 "In16.Cu" signal "GND7")
		(2 "B.Cu" signal "BOTTOM")
		(9 "F.Adhes" user "F.Adhesive")
		(11 "B.Adhes" user "B.Adhesive")
		(13 "F.Paste" user "Package Geometry/Pastemask Top")
		(15 "B.Paste" user "Package Geometry/Pastemask Bottom")
		(5 "F.SilkS" user "Ref Des/Silkscreen Top")
		(7 "B.SilkS" user "Ref Des/Silkscreen Bottom")
		(1 "F.Mask" user "Board Geometry/Soldermask Top")
		(3 "B.Mask" user "Board Geometry/Soldermask Bottom")
		(17 "Dwgs.User" user "User.Drawings")
		(19 "Cmts.User" user "User.Comments")
		(21 "Eco1.User" user "User.Eco1")
		(23 "Eco2.User" user "User.Eco2")
		(25 "Edge.Cuts" user "Board Geometry/Outline")
		(27 "Margin" user)
		(31 "F.CrtYd" user "Package Geometry/Place Bound Top")
		(29 "B.CrtYd" user "Package Geometry/Place Bound Bottom")
		(35 "F.Fab" user "Ref Des/Assembly Top")
		(33 "B.Fab" user "Ref Des/Assembly Bottom")
	)
	(footprint ""
		(layer "F.Cu")
		(at 160.402016 -10.849864 -90)
		(property "Reference" "J41"
			(at -8.65886 -21.78558 0)
			(unlocked yes)
			(layer "F.SilkS")
			(effects
				(font
					(size 0.7874 0.5842)
					(thickness 0.1524)
				)
				(justify left)
			)
		)
		(property "Value" ""
			(at 0 0 270)
			(layer "F.Fab")
			(effects
				(font
					(size 1.27 1.27)
				)
			)
		)
		(duplicate_pad_numbers_are_jumpers no)
		(pad "" np_thru_hole circle
			(at -0.599948 -32.079946 180)
			(size 1.1176 1.1176)
			(drill 1.1176)
			(layers "*.Cu" "*.Mask")
			(clearance 0.381)
			(thermal_gap 0.381)
		)
		(pad "" np_thru_hole circle
			(at 0.40005 32.085026 180)
			(size 1.1176 1.1176)
			(drill 1.1176)
			(layers "*.Cu" "*.Mask")
			(clearance 0.381)
			(thermal_gap 0.381)
		)
		(pad "A1" smd rect
			(at -2.750058 -18.465038 180)
			(size 0.381 1.4478)
			(layers "F.Cu" "F.Mask" "F.Paste")
			(net "SMB_OCP_SFF_3V3AUX_SCL_R0")
		)
		(pad "A2" smd rect
			(at -2.750058 -17.86509 180)
			(size 0.381 1.4478)
			(layers "F.Cu" "F.Mask" "F.Paste")
			(net "SMB_OCP_SFF_3V3AUX_SDA_R0")
		)
		(pad "A3" smd rect
			(at -2.750058 -17.264888 180)
			(size 0.381 1.4478)
			(layers "F.Cu" "F.Mask" "F.Paste")
			(net "SMB_CPU0_CPU1_APML_SCL_R")
		)
		(pad "A4" smd rect
			(at -2.750058 -16.66494 180)
			(size 0.381 1.4478)
			(layers "F.Cu" "F.Mask" "F.Paste")
			(net "SMB_CPU0_CPU1_APML_SDA_R")
		)
		(pad "A5" smd rect
			(at -2.750058 -16.064992 180)
			(size 0.381 1.4478)
			(layers "F.Cu" "F.Mask" "F.Paste")
			(net "SMB_VR_3V3AUX_SCL_R0")
		)
		(pad "A6" smd rect
			(at -2.750058 -15.465044 180)
			(size 0.381 1.4478)
			(layers "F.Cu" "F.Mask" "F.Paste")
			(net "SMB_VR_3V3AUX_SDA_R0")
		)
		(pad "A7" smd rect
			(at -2.750058 -14.865096 180)
			(size 0.381 1.4478)
			(layers "F.Cu" "F.Mask" "F.Paste")
			(net "SMB_CPU0_CPU1_SEC_SCL_R")
		)
		(pad "A8" smd rect
			(at -2.750058 -14.264894 180)
			(size 0.381 1.4478)
			(layers "F.Cu" "F.Mask" "F.Paste")
			(net "SMB_CPU0_CPU1_SEC_SDA_R")
		)
		(pad "A9" smd rect
			(at -2.750058 -13.664946 180)
			(size 0.381 1.4478)
			(layers "F.Cu" "F.Mask" "F.Paste")
			(net "I3C_BMC_SWB_SCL")
		)
		(pad "A10" smd rect
			(at -2.750058 -13.064998 180)
			(size 0.381 1.4478)
			(layers "F.Cu" "F.Mask" "F.Paste")
			(net "I3C_BMC_SWB_SDA")
		)
		(pad "A11" smd rect
			(at -2.750058 -12.46505 180)
			(size 0.381 1.4478)
			(layers "F.Cu" "F.Mask" "F.Paste")
			(net "SMB_OCP_V3_2_3V3AUX_SCL_R0")
		)
		(pad "A12" smd rect
			(at -2.750058 -11.865102 180)
			(size 0.381 1.4478)
			(layers "F.Cu" "F.Mask" "F.Paste")
			(net "SMB_OCP_V3_2_3V3AUX_SDA_R0")
		)
		(pad "A13" smd rect
			(at -2.750058 -11.2649 180)
			(size 0.381 1.4478)
			(layers "F.Cu" "F.Mask" "F.Paste")
			(net "GND")
		)
		(pad "A14" smd rect
			(at -2.750058 -10.664952 180)
			(size 0.381 1.4478)
			(layers "F.Cu" "F.Mask" "F.Paste")
			(net "CLK_100M_CPU0_CLK01_DP")
		)
		(pad "A15" smd rect
			(at -2.750058 -10.065004 180)
			(size 0.381 1.4478)
			(layers "F.Cu" "F.Mask" "F.Paste")
			(net "CLK_100M_CPU0_CLK01_DN")
		)
		(pad "A16" smd rect
			(at -2.750058 -9.465056 180)
			(size 0.381 1.4478)
			(layers "F.Cu" "F.Mask" "F.Paste")
			(net "GND")
		)
		(pad "A17" smd rect
			(at -2.750058 -8.865108 180)
			(size 0.381 1.4478)
			(layers "F.Cu" "F.Mask" "F.Paste")
			(net "P2E_CPU0_P5_TX_C_DP")
		)
		(pad "A18" smd rect
			(at -2.750058 -8.264906 180)
			(size 0.381 1.4478)
			(layers "F.Cu" "F.Mask" "F.Paste")
			(net "P2E_CPU0_P5_TX_C_DN")
		)
		(pad "A19" smd rect
			(at -2.750058 -7.664958 180)
			(size 0.381 1.4478)
			(layers "F.Cu" "F.Mask" "F.Paste")
			(net "GND")
		)
		(pad "A20" smd rect
			(at -2.750058 -7.06501 180)
			(size 0.381 1.4478)
			(layers "F.Cu" "F.Mask" "F.Paste")
			(net "P2E_CPU0_P5_RX_DP")
		)
		(pad "A21" smd rect
			(at -2.750058 -6.465062 180)
			(size 0.381 1.4478)
			(layers "F.Cu" "F.Mask" "F.Paste")
			(net "P2E_CPU0_P5_RX_DN")
		)
		(pad "A22" smd rect
			(at -2.750058 -5.865114 180)
			(size 0.381 1.4478)
			(layers "F.Cu" "F.Mask" "F.Paste")
			(net "GND")
		)
		(pad "A23" smd rect
			(at -2.750058 -5.264912 180)
			(size 0.381 1.4478)
			(layers "F.Cu" "F.Mask" "F.Paste")
			(net "SMB_PCIE0_3V3AUX_SCL")
		)
		(pad "A24" smd rect
			(at -2.750058 -4.664964 180)
			(size 0.381 1.4478)
			(layers "F.Cu" "F.Mask" "F.Paste")
			(net "SMB_PCIE0_3V3AUX_SDA")
		)
		(pad "A25" smd rect
			(at -2.750058 -4.065016 180)
			(size 0.381 1.4478)
			(layers "F.Cu" "F.Mask" "F.Paste")
			(net "SMB_PMBUS_3V3AUX_SCL_R0")
		)
		(pad "A26" smd rect
			(at -2.750058 -3.465068 180)
			(size 0.381 1.4478)
			(layers "F.Cu" "F.Mask" "F.Paste")
			(net "SMB_PMBUS_3V3AUX_SDA_R0")
		)
		(pad "A27" smd rect
			(at -2.750058 -2.86512 180)
			(size 0.381 1.4478)
			(layers "F.Cu" "F.Mask" "F.Paste")
			(net "SMB_1_PLD_3V3AUX_SCL_R3")
		)
		(pad "A28" smd rect
			(at -2.750058 -2.264918 180)
			(size 0.381 1.4478)
			(layers "F.Cu" "F.Mask" "F.Paste")
			(net "SMB_1_PLD_3V3AUX_SDA_R3")
		)
		(pad "A29" smd rect
			(at -2.750058 1.74498 180)
			(size 0.381 1.4478)
			(layers "F.Cu" "F.Mask" "F.Paste")
			(net "SMB_FAN_3V3AUX_SCL")
		)
		(pad "A30" smd rect
			(at -2.750058 2.344928 180)
			(size 0.381 1.4478)
			(layers "F.Cu" "F.Mask" "F.Paste")
			(net "SMB_FAN_3V3AUX_SDA")
		)
		(pad "A31" smd rect
			(at -2.750058 2.944876 180)
			(size 0.381 1.4478)
			(layers "F.Cu" "F.Mask" "F.Paste")
			(net "SMB_PCIE2_3V3AUX_SCL_R0")
		)
		(pad "A32" smd rect
			(at -2.750058 3.545078 180)
			(size 0.381 1.4478)
			(layers "F.Cu" "F.Mask" "F.Paste")
			(net "SMB_PCIE2_3V3AUX_SDA_R0")
		)
		(pad "A33" smd rect
			(at -2.750058 4.145026 180)
			(size 0.381 1.4478)
			(layers "F.Cu" "F.Mask" "F.Paste")
			(net "GND")
		)
		(pad "A34" smd rect
			(at -2.750058 4.744974 180)
			(size 0.381 1.4478)
			(layers "F.Cu" "F.Mask" "F.Paste")
			(net "JTAG_SCM_TCK")
		)
		(pad "A35" smd rect
			(at -2.750058 5.344922 180)
			(size 0.381 1.4478)
			(layers "F.Cu" "F.Mask" "F.Paste")
			(net "JTAG_SCM_TMS")
		)
		(pad "A36" smd rect
			(at -2.750058 5.945124 180)
			(size 0.381 1.4478)
			(layers "F.Cu" "F.Mask" "F.Paste")
			(net "JTAG_SCM_TDI_R")
		)
		(pad "A37" smd rect
			(at -2.750058 6.545072 180)
			(size 0.381 1.4478)
			(layers "F.Cu" "F.Mask" "F.Paste")
			(net "JTAG_SCM_TDO_R")
		)
		(pad "A38" smd rect
			(at -2.750058 7.14502 180)
			(size 0.381 1.4478)
			(layers "F.Cu" "F.Mask" "F.Paste")
			(net "SMB_PCIE3_3V3AUX_SCL_R")
		)
		(pad "A39" smd rect
			(at -2.750058 7.744968 180)
			(size 0.381 1.4478)
			(layers "F.Cu" "F.Mask" "F.Paste")
			(net "SMB_PCIE3_3V3AUX_SDA_R")
		)
		(pad "A40" smd rect
			(at -2.750058 8.344916 180)
			(size 0.381 1.4478)
			(layers "F.Cu" "F.Mask" "F.Paste")
			(net "SMB_HOST_CLK_3V3AUX_SCL_R0")
		)
		(pad "A41" smd rect
			(at -2.750058 8.945118 180)
			(size 0.381 1.4478)
			(layers "F.Cu" "F.Mask" "F.Paste")
			(net "SMB_HOST_CLK_3V3AUX_SDA_R0")
		)
		(pad "A42" smd rect
			(at -2.750058 9.545066 180)
			(size 0.381 1.4478)
			(layers "F.Cu" "F.Mask" "F.Paste")
			(net "GND")
		)
		(pad "A43" smd rect
			(at -2.750058 14.454886 180)
			(size 0.381 1.4478)
			(layers "F.Cu" "F.Mask" "F.Paste")
			(net "FW_RECOVERY")
		)
		(pad "A44" smd rect
			(at -2.750058 15.055088 180)
			(size 0.381 1.4478)
			(layers "F.Cu" "F.Mask" "F.Paste")
			(net "PWRGD_PS_PWROK_R")
		)
		(pad "A45" smd rect
			(at -2.750058 15.655036 180)
			(size 0.381 1.4478)
			(layers "F.Cu" "F.Mask" "F.Paste")
			(net "TP_STBY_EN")
		)
		(pad "A46" smd rect
			(at -2.750058 16.254984 180)
			(size 0.381 1.4478)
			(layers "F.Cu" "F.Mask" "F.Paste")
			(net "RST_MB_STBY_R_N")
		)
		(pad "A47" smd rect
			(at -2.750058 16.854932 180)
			(size 0.381 1.4478)
			(layers "F.Cu" "F.Mask" "F.Paste")
			(net "SCM_SYS_PWRBTN_R_N")
		)
		(pad "A48" smd rect
			(at -2.750058 17.45488 180)
			(size 0.381 1.4478)
			(layers "F.Cu" "F.Mask" "F.Paste")
			(net "SCM_SYS_PWROK_R1")
		)
		(pad "A49" smd rect
			(at -2.750058 18.055082 180)
			(size 0.381 1.4478)
			(layers "F.Cu" "F.Mask" "F.Paste")
			(net "SCM_HDT_DBREQ_N")
		)
		(pad "A50" smd rect
			(at -2.750058 18.65503 180)
			(size 0.381 1.4478)
			(layers "F.Cu" "F.Mask" "F.Paste")
			(net "PU_JTAG_DBP_BMC_PRDY_N")
		)
		(pad "A51" smd rect
			(at -2.750058 19.254978 180)
			(size 0.381 1.4478)
			(layers "F.Cu" "F.Mask" "F.Paste")
			(net "FM_RST_PERST_SCM_N")
		)
		(pad "A52" smd rect
			(at -2.750058 19.854926 180)
			(size 0.381 1.4478)
			(layers "F.Cu" "F.Mask" "F.Paste")
			(net "FM_UARTSW_MSB_R")
		)
		(pad "A53" smd rect
			(at -2.750058 20.455128 180)
			(size 0.381 1.4478)
			(layers "F.Cu" "F.Mask" "F.Paste")
			(net "SCM_ROT_CPU_RST_N")
		)
		(pad "A54" smd rect
			(at -2.750058 21.055076 180)
			(size 0.381 1.4478)
			(layers "F.Cu" "F.Mask" "F.Paste")
			(net "TP_CHASI")
		)
		(pad "A55" smd rect
			(at -2.750058 21.655024 180)
			(size 0.381 1.4478)
			(layers "F.Cu" "F.Mask" "F.Paste")
			(net "FM_UARTSW_LSB_R")
		)
		(pad "A56" smd rect
			(at -2.750058 22.254972 180)
			(size 0.381 1.4478)
			(layers "F.Cu" "F.Mask" "F.Paste")
			(net "IRQ0_A56")
		)
		(pad "A57" smd rect
			(at -2.750058 22.85492 180)
			(size 0.381 1.4478)
			(layers "F.Cu" "F.Mask" "F.Paste")
			(net "FM_SCM_PRSNT1_N")
		)
		(pad "A58" smd rect
			(at -2.750058 23.455122 180)
			(size 0.381 1.4478)
			(layers "F.Cu" "F.Mask" "F.Paste")
			(net "GND")
		)
		(pad "A59" smd rect
			(at -2.750058 24.05507 180)
			(size 0.381 1.4478)
			(layers "F.Cu" "F.Mask" "F.Paste")
			(net "USB3_CPU0_BMC_RX_DP")
		)
		(pad "A60" smd rect
			(at -2.750058 24.655018 180)
			(size 0.381 1.4478)
			(layers "F.Cu" "F.Mask" "F.Paste")
			(net "USB3_CPU0_BMC_RX_DN")
		)
		(pad "A61" smd rect
			(at -2.750058 25.254966 180)
			(size 0.381 1.4478)
			(layers "F.Cu" "F.Mask" "F.Paste")
			(net "GND")
		)
		(pad "A62" smd rect
			(at -2.750058 25.854914 180)
			(size 0.381 1.4478)
			(layers "F.Cu" "F.Mask" "F.Paste")
			(net "TP_PCIE_RXP<1>")
		)
		(pad "A63" smd rect
			(at -2.750058 26.455116 180)
			(size 0.381 1.4478)
			(layers "F.Cu" "F.Mask" "F.Paste")
			(net "TP_PCIE_RXN<1>")
		)
		(pad "A64" smd rect
			(at -2.750058 27.055064 180)
			(size 0.381 1.4478)
			(layers "F.Cu" "F.Mask" "F.Paste")
			(net "GND")
		)
		(pad "A65" smd rect
			(at -2.750058 27.655012 180)
			(size 0.381 1.4478)
			(layers "F.Cu" "F.Mask" "F.Paste")
			(net "P2E_MB_BMC_RX_BUF_DP<0>")
		)
		(pad "A66" smd rect
			(at -2.750058 28.25496 180)
			(size 0.381 1.4478)
			(layers "F.Cu" "F.Mask" "F.Paste")
			(net "P2E_MB_BMC_RX_BUF_DN<0>")
		)
		(pad "A67" smd rect
			(at -2.750058 28.854908 180)
			(size 0.381 1.4478)
			(layers "F.Cu" "F.Mask" "F.Paste")
			(net "GND")
		)
		(pad "A68" smd rect
			(at -2.750058 29.45511 180)
			(size 0.381 1.4478)
			(layers "F.Cu" "F.Mask" "F.Paste")
			(net "CLK_100M_BMC_RC_DP")
		)
		(pad "A69" smd rect
			(at -2.750058 30.055058 180)
			(size 0.381 1.4478)
			(layers "F.Cu" "F.Mask" "F.Paste")
			(net "CLK_100M_BMC_RC_DN")
		)
		(pad "A70" smd rect
			(at -2.750058 30.655006 180)
			(size 0.381 1.4478)
			(layers "F.Cu" "F.Mask" "F.Paste")
			(net "GND")
		)
		(pad "B1" smd rect
			(at -5.700014 -18.465038 180)
			(size 0.381 1.4478)
			(layers "F.Cu" "F.Mask" "F.Paste")
			(net "CLK_ESPI_CPU0_CLK1")
		)
		(pad "B2" smd rect
			(at -5.700014 -17.86509 180)
			(size 0.381 1.4478)
			(layers "F.Cu" "F.Mask" "F.Paste")
			(net "ESPI_CPU0_CS1_N")
		)
		(pad "B3" smd rect
			(at -5.700014 -17.264888 180)
			(size 0.381 1.4478)
			(layers "F.Cu" "F.Mask" "F.Paste")
			(net "ESPI_CPU0_ALERT_N")
		)
		(pad "B4" smd rect
			(at -5.700014 -16.66494 180)
			(size 0.381 1.4478)
			(layers "F.Cu" "F.Mask" "F.Paste")
			(net "RST_ESPI_CPU0_RSTOUT_N")
		)
		(pad "B5" smd rect
			(at -5.700014 -16.064992 180)
			(size 0.381 1.4478)
			(layers "F.Cu" "F.Mask" "F.Paste")
			(net "ESPI_CPU0_D0")
		)
		(pad "B6" smd rect
			(at -5.700014 -15.465044 180)
			(size 0.381 1.4478)
			(layers "F.Cu" "F.Mask" "F.Paste")
			(net "ESPI_CPU0_D1")
		)
		(pad "B7" smd rect
			(at -5.700014 -14.865096 180)
			(size 0.381 1.4478)
			(layers "F.Cu" "F.Mask" "F.Paste")
			(net "ESPI_CPU0_D2")
		)
		(pad "B8" smd rect
			(at -5.700014 -14.264894 180)
			(size 0.381 1.4478)
			(layers "F.Cu" "F.Mask" "F.Paste")
			(net "ESPI_CPU0_D3")
		)
		(pad "B9" smd rect
			(at -5.700014 -13.664946 180)
			(size 0.381 1.4478)
			(layers "F.Cu" "F.Mask" "F.Paste")
			(net "FM_LPC_ESPI_SEL")
		)
		(pad "B10" smd rect
			(at -5.700014 -13.064998 180)
			(size 0.381 1.4478)
			(layers "F.Cu" "F.Mask" "F.Paste")
			(net "GND")
		)
		(pad "B11" smd rect
			(at -5.700014 -12.46505 180)
			(size 0.381 1.4478)
			(layers "F.Cu" "F.Mask" "F.Paste")
			(net "SPI_CPU0_LVC3_SCM_CLK")
		)
		(pad "B12" smd rect
			(at -5.700014 -11.865102 180)
			(size 0.381 1.4478)
			(layers "F.Cu" "F.Mask" "F.Paste")
			(net "SPI_CPU0_LVC3_SCM_CS0_N")
		)
		(pad "B13" smd rect
			(at -5.700014 -11.2649 180)
			(size 0.381 1.4478)
			(layers "F.Cu" "F.Mask" "F.Paste")
			(net "SPI_CPU0_LVC3_SCM_D0")
		)
		(pad "B14" smd rect
			(at -5.700014 -10.664952 180)
			(size 0.381 1.4478)
			(layers "F.Cu" "F.Mask" "F.Paste")
			(net "SPI_CPU0_LVC3_SCM_D1")
		)
		(pad "B15" smd rect
			(at -5.700014 -10.065004 180)
			(size 0.381 1.4478)
			(layers "F.Cu" "F.Mask" "F.Paste")
			(net "SPI_CPU0_LVC3_SCM_D2")
		)
		(pad "B16" smd rect
			(at -5.700014 -9.465056 180)
			(size 0.381 1.4478)
			(layers "F.Cu" "F.Mask" "F.Paste")
			(net "SPI_CPU0_LVC3_SCM_D3")
		)
		(pad "B17" smd rect
			(at -5.700014 -8.865108 180)
			(size 0.381 1.4478)
			(layers "F.Cu" "F.Mask" "F.Paste")
			(net "GND")
		)
		(pad "B18" smd rect
			(at -5.700014 -8.264906 180)
			(size 0.381 1.4478)
			(layers "F.Cu" "F.Mask" "F.Paste")
			(net "CLK_50M_RMII_BMC_OCP")
		)
		(pad "B19" smd rect
			(at -5.700014 -7.664958 180)
			(size 0.381 1.4478)
			(layers "F.Cu" "F.Mask" "F.Paste")
			(net "RMII_OCP_BMC_CRSDV")
		)
		(pad "B20" smd rect
			(at -5.700014 -7.06501 180)
			(size 0.381 1.4478)
			(layers "F.Cu" "F.Mask" "F.Paste")
			(net "RMII_BMC_OCP_TX_EN")
		)
		(pad "B21" smd rect
			(at -5.700014 -6.465062 180)
			(size 0.381 1.4478)
			(layers "F.Cu" "F.Mask" "F.Paste")
			(net "RMII_BMC_OCP_TXD_0")
		)
		(pad "B22" smd rect
			(at -5.700014 -5.865114 180)
			(size 0.381 1.4478)
			(layers "F.Cu" "F.Mask" "F.Paste")
			(net "RMII_BMC_OCP_TXD_1")
		)
		(pad "B23" smd rect
			(at -5.700014 -5.264912 180)
			(size 0.381 1.4478)
			(layers "F.Cu" "F.Mask" "F.Paste")
			(net "RMII_BMC_OCP_RX_ER")
		)
		(pad "B24" smd rect
			(at -5.700014 -4.664964 180)
			(size 0.381 1.4478)
			(layers "F.Cu" "F.Mask" "F.Paste")
			(net "RMII_OCP_BMC_RXD_0")
		)
		(pad "B25" smd rect
			(at -5.700014 -4.065016 180)
			(size 0.381 1.4478)
			(layers "F.Cu" "F.Mask" "F.Paste")
			(net "RMII_OCP_BMC_RXD_1")
		)
		(pad "B26" smd rect
			(at -5.700014 -3.465068 180)
			(size 0.381 1.4478)
			(layers "F.Cu" "F.Mask" "F.Paste")
			(net "GND")
		)
		(pad "B27" smd rect
			(at -5.700014 -2.86512 180)
			(size 0.381 1.4478)
			(layers "F.Cu" "F.Mask" "F.Paste")
			(net "TP_PECI_BMC")
		)
		(pad "B28" smd rect
			(at -5.700014 -2.264918 180)
			(size 0.381 1.4478)
			(layers "F.Cu" "F.Mask" "F.Paste")
			(net "TP_PVCCIO_PECI_BMC")
		)
		(pad "B29" smd rect
			(at -5.700014 1.74498 180)
			(size 0.381 1.4478)
			(layers "F.Cu" "F.Mask" "F.Paste")
			(net "SGPIO_SCM_DO_R_<0>")
		)
		(pad "B30" smd rect
			(at -5.700014 2.344928 180)
			(size 0.381 1.4478)
			(layers "F.Cu" "F.Mask" "F.Paste")
			(net "SGPIO_SCM_CLK_R_<0>")
		)
		(pad "B31" smd rect
			(at -5.700014 2.944876 180)
			(size 0.381 1.4478)
			(layers "F.Cu" "F.Mask" "F.Paste")
			(net "SGPIO_SCM_DI_R_<0>")
		)
		(pad "B32" smd rect
			(at -5.700014 3.545078 180)
			(size 0.381 1.4478)
			(layers "F.Cu" "F.Mask" "F.Paste")
			(net "SGPIO_SCM_LD_R_<0>")
		)
		(pad "B33" smd rect
			(at -5.700014 4.145026 180)
			(size 0.381 1.4478)
			(layers "F.Cu" "F.Mask" "F.Paste")
			(net "GND")
		)
		(pad "B34" smd rect
			(at -5.700014 4.744974 180)
			(size 0.381 1.4478)
			(layers "F.Cu" "F.Mask" "F.Paste")
			(net "SGPIO_SCM_DO_R_<1>")
		)
		(pad "B35" smd rect
			(at -5.700014 5.344922 180)
			(size 0.381 1.4478)
			(layers "F.Cu" "F.Mask" "F.Paste")
			(net "SGPIO_SCM_CLK_R_<1>")
		)
	)
)
